(kicad_pcb
	(version 20260206)
	(generator "pcbnew")
	(generator_version "10.0")
	(general
		(thickness 1.6)
		(legacy_teardrops no)
	)
	(paper "A4")
	(title_block
		(title "04192023_DAF0TMB3IC0_F0TG_MB_C_brd_V02_OCP.brd")
		(comment 1 "Grand Teton / footprints 3086-3091 of 8354")
	)
	(layers
		(0 "F.Cu" signal "TOP")
		(4 "In1.Cu" signal "GND")
		(6 "In2.Cu" signal "IN1")
		(8 "In3.Cu" signal "GND1")
		(10 "In4.Cu" signal "IN2")
		(12 "In5.Cu" signal "GND2")
		(14 "In6.Cu" signal "IN3")
		(16 "In7.Cu" signal "GND3")
		(18 "In8.Cu" signal "VCC")
		(20 "In9.Cu" signal "VCC1")
		(22 "In10.Cu" signal "GND4")
		(24 "In11.Cu" signal "IN4")
		(26 "In12.Cu" signal "GND5")
		(28 "In13.Cu" signal "IN5")
		(30 "In14.Cu" signal "GND6")
		(32 "In15.Cu" signal "IN6")
		(34 "In16.Cu" signal "GND7")
		(2 "B.Cu" signal "BOTTOM")
		(9 "F.Adhes" user "F.Adhesive")
		(11 "B.Adhes" user "B.Adhesive")
		(13 "F.Paste" user "Package Geometry/Pastemask Top")
		(15 "B.Paste" user "Package Geometry/Pastemask Bottom")
		(5 "F.SilkS" user "Ref Des/Silkscreen Top")
		(7 "B.SilkS" user "Ref Des/Silkscreen Bottom")
		(1 "F.Mask" user "Board Geometry/Soldermask Top")
		(3 "B.Mask" user "Board Geometry/Soldermask Bottom")
		(17 "Dwgs.User" user "User.Drawings")
		(19 "Cmts.User" user "User.Comments")
		(21 "Eco1.User" user "User.Eco1")
		(23 "Eco2.User" user "User.Eco2")
		(25 "Edge.Cuts" user "Board Geometry/Outline")
		(27 "Margin" user)
		(31 "F.CrtYd" user "Package Geometry/Place Bound Top")
		(29 "B.CrtYd" user "Package Geometry/Place Bound Bottom")
		(35 "F.Fab" user "Ref Des/Assembly Top")
		(33 "B.Fab" user "Ref Des/Assembly Bottom")
	)
	(footprint ""
		(layer "F.Cu")
		(at 271.092676 -119.761)
		(property "Reference" "R1315"
			(at 0 0 0)
			(layer "F.SilkS")
			(hide yes)
			(effects
				(font
					(size 1.27 1.27)
				)
			)
		)
		(property "Value" ""
			(at 0 0 0)
			(layer "F.Fab")
			(effects
				(font
					(size 1.27 1.27)
				)
			)
		)
		(duplicate_pad_numbers_are_jumpers no)
		(fp_line
			(start -0.7874 -0.4064)
			(end 0.7874 -0.4064)
			(stroke
				(width 0.1524)
				(type default)
			)
			(layer "F.SilkS")
		)
		(fp_line
			(start -0.7874 0.4064)
			(end -0.7874 -0.4064)
			(stroke
				(width 0.1524)
				(type default)
			)
			(layer "F.SilkS")
		)
		(fp_line
			(start 0.7874 -0.4064)
			(end 0.7874 0.4064)
			(stroke
				(width 0.1524)
				(type default)
			)
			(layer "F.SilkS")
		)
		(fp_line
			(start 0.7874 0.4064)
			(end -0.7874 0.4064)
			(stroke
				(width 0.1524)
				(type default)
			)
			(layer "F.SilkS")
		)
		(fp_line
			(start -0.67945 -0.305054)
			(end -0.12065 -0.305054)
			(stroke
				(width 0.1)
				(type default)
			)
			(layer "F.Fab")
		)
		(fp_line
			(start -0.67945 0.3048)
			(end -0.67945 -0.305054)
			(stroke
				(width 0.1)
				(type default)
			)
			(layer "F.Fab")
		)
		(fp_line
			(start -0.12065 -0.305054)
			(end -0.12065 -0.2794)
			(stroke
				(width 0.1)
				(type default)
			)
			(layer "F.Fab")
		)
		(fp_line
			(start -0.12065 -0.2794)
			(end 0.12065 -0.2794)
			(stroke
				(width 0.1)
				(type default)
			)
			(layer "F.Fab")
		)
		(fp_line
			(start -0.12065 0.2794)
			(end -0.12065 0.3048)
			(stroke
				(width 0.1)
				(type default)
			)
			(layer "F.Fab")
		)
		(fp_line
			(start -0.12065 0.3048)
			(end -0.67945 0.3048)
			(stroke
				(width 0.1)
				(type default)
			)
			(layer "F.Fab")
		)
		(fp_line
			(start 0.120396 0.2794)
			(end -0.12065 0.2794)
			(stroke
				(width 0.1)
				(type default)
			)
			(layer "F.Fab")
		)
		(fp_line
			(start 0.120396 0.3048)
			(end 0.120396 0.2794)
			(stroke
				(width 0.1)
				(type default)
			)
			(layer "F.Fab")
		)
		(fp_line
			(start 0.12065 -0.3048)
			(end 0.67945 -0.3048)
			(stroke
				(width 0.1)
				(type default)
			)
			(layer "F.Fab")
		)
		(fp_line
			(start 0.12065 -0.2794)
			(end 0.12065 -0.3048)
			(stroke
				(width 0.1)
				(type default)
			)
			(layer "F.Fab")
		)
		(fp_line
			(start 0.67945 -0.3048)
			(end 0.67945 0.3048)
			(stroke
				(width 0.1)
				(type default)
			)
			(layer "F.Fab")
		)
		(fp_line
			(start 0.67945 0.3048)
			(end 0.120396 0.3048)
			(stroke
				(width 0.1)
				(type default)
			)
			(layer "F.Fab")
		)
		(pad "1" smd circle
			(at -0.40005 0)
			(size 0 0)
			(layers "F.Cu" "F.Mask" "F.Paste")
			(net "SMB_ADC_SCL")
		)
		(pad "2" smd circle
			(at 0.40005 0)
			(size 0 0)
			(layers "F.Cu" "F.Mask" "F.Paste")
			(net "SMB_ADC_SCL_R")
		)
	)
	(footprint ""
		(layer "F.Cu")
		(at 257.766312 -69.196458 90)
		(property "Reference" "R4072"
			(at 0 0 90)
			(layer "F.SilkS")
			(hide yes)
			(effects
				(font
					(size 1.27 1.27)
				)
			)
		)
		(property "Value" ""
			(at 0 0 90)
			(layer "F.Fab")
			(effects
				(font
					(size 1.27 1.27)
				)
			)
		)
		(duplicate_pad_numbers_are_jumpers no)
		(fp_line
			(start 0.7874 -0.4064)
			(end 0.7874 0.4064)
			(stroke
				(width 0.1524)
				(type default)
			)
			(layer "F.SilkS")
		)
		(fp_line
			(start -0.7874 -0.4064)
			(end 0.7874 -0.4064)
			(stroke
				(width 0.1524)
				(type default)
			)
			(layer "F.SilkS")
		)
		(fp_line
			(start 0.7874 0.4064)
			(end -0.7874 0.4064)
			(stroke
				(width 0.1524)
				(type default)
			)
			(layer "F.SilkS")
		)
		(fp_line
			(start -0.7874 0.4064)
			(end -0.7874 -0.4064)
			(stroke
				(width 0.1524)
				(type default)
			)
			(layer "F.SilkS")
		)
		(fp_line
			(start -0.12065 -0.305054)
			(end -0.12065 -0.2794)
			(stroke
				(width 0.1)
				(type default)
			)
			(layer "F.Fab")
		)
		(fp_line
			(start -0.67945 -0.305054)
			(end -0.12065 -0.305054)
			(stroke
				(width 0.1)
				(type default)
			)
			(layer "F.Fab")
		)
		(fp_line
			(start 0.67945 -0.3048)
			(end 0.67945 0.3048)
			(stroke
				(width 0.1)
				(type default)
			)
			(layer "F.Fab")
		)
		(fp_line
			(start 0.12065 -0.3048)
			(end 0.67945 -0.3048)
			(stroke
				(width 0.1)
				(type default)
			)
			(layer "F.Fab")
		)
		(fp_line
			(start 0.12065 -0.2794)
			(end 0.12065 -0.3048)
			(stroke
				(width 0.1)
				(type default)
			)
			(layer "F.Fab")
		)
		(fp_line
			(start -0.12065 -0.2794)
			(end 0.12065 -0.2794)
			(stroke
				(width 0.1)
				(type default)
			)
			(layer "F.Fab")
		)
		(fp_line
			(start 0.120396 0.2794)
			(end -0.12065 0.2794)
			(stroke
				(width 0.1)
				(type default)
			)
			(layer "F.Fab")
		)
		(fp_line
			(start -0.12065 0.2794)
			(end -0.12065 0.3048)
			(stroke
				(width 0.1)
				(type default)
			)
			(layer "F.Fab")
		)
		(fp_line
			(start 0.67945 0.3048)
			(end 0.120396 0.3048)
			(stroke
				(width 0.1)
				(type default)
			)
			(layer "F.Fab")
		)
		(fp_line
			(start 0.120396 0.3048)
			(end 0.120396 0.2794)
			(stroke
				(width 0.1)
				(type default)
			)
			(layer "F.Fab")
		)
		(fp_line
			(start -0.12065 0.3048)
			(end -0.67945 0.3048)
			(stroke
				(width 0.1)
				(type default)
			)
			(layer "F.Fab")
		)
		(fp_line
			(start -0.67945 0.3048)
			(end -0.67945 -0.305054)
			(stroke
				(width 0.1)
				(type default)
			)
			(layer "F.Fab")
		)
		(pad "1" smd circle
			(at -0.40005 0 90)
			(size 0 0)
			(layers "F.Cu" "F.Mask" "F.Paste")
			(net "P12V_AUX")
		)
		(pad "2" smd circle
			(at 0.40005 0 90)
			(size 0 0)
			(layers "F.Cu" "F.Mask" "F.Paste")
			(net "P3V3_E1S_0_EN_G")
		)
	)
	(footprint ""
		(layer "F.Cu")
		(at 461.957928 -94.317566)
		(property "Reference" "C1840"
			(at 0 0 0)
			(layer "F.SilkS")
			(hide yes)
			(effects
				(font
					(size 1.27 1.27)
				)
			)
		)
		(property "Value" ""
			(at 0 0 0)
			(layer "F.Fab")
			(effects
				(font
					(size 1.27 1.27)
				)
			)
		)
		(duplicate_pad_numbers_are_jumpers no)
		(fp_line
			(start -0.7874 -0.4064)
			(end 0.7874 -0.4064)
			(stroke
				(width 0.1524)
				(type default)
			)
			(layer "F.SilkS")
		)
		(fp_line
			(start -0.7874 0.4064)
			(end -0.7874 -0.4064)
			(stroke
				(width 0.1524)
				(type default)
			)
			(layer "F.SilkS")
		)
		(fp_line
			(start 0.7874 -0.4064)
			(end 0.7874 0.4064)
			(stroke
				(width 0.1524)
				(type default)
			)
			(layer "F.SilkS")
		)
		(fp_line
			(start 0.7874 0.4064)
			(end -0.7874 0.4064)
			(stroke
				(width 0.1524)
				(type default)
			)
			(layer "F.SilkS")
		)
		(fp_line
			(start -0.67945 -0.305054)
			(end -0.12065 -0.305054)
			(stroke
				(width 0.1)
				(type default)
			)
			(layer "F.Fab")
		)
		(fp_line
			(start -0.67945 0.3048)
			(end -0.67945 -0.305054)
			(stroke
				(width 0.1)
				(type default)
			)
			(layer "F.Fab")
		)
		(fp_line
			(start -0.12065 -0.305054)
			(end -0.12065 -0.2794)
			(stroke
				(width 0.1)
				(type default)
			)
			(layer "F.Fab")
		)
		(fp_line
			(start -0.12065 -0.2794)
			(end 0.12065 -0.2794)
			(stroke
				(width 0.1)
				(type default)
			)
			(layer "F.Fab")
		)
		(fp_line
			(start -0.12065 0.2794)
			(end -0.12065 0.3048)
			(stroke
				(width 0.1)
				(type default)
			)
			(layer "F.Fab")
		)
		(fp_line
			(start -0.12065 0.3048)
			(end -0.67945 0.3048)
			(stroke
				(width 0.1)
				(type default)
			)
			(layer "F.Fab")
		)
		(fp_line
			(start 0.120396 0.2794)
			(end -0.12065 0.2794)
			(stroke
				(width 0.1)
				(type default)
			)
			(layer "F.Fab")
		)
		(fp_line
			(start 0.120396 0.3048)
			(end 0.120396 0.2794)
			(stroke
				(width 0.1)
				(type default)
			)
			(layer "F.Fab")
		)
		(fp_line
			(start 0.12065 -0.3048)
			(end 0.67945 -0.3048)
			(stroke
				(width 0.1)
				(type default)
			)
			(layer "F.Fab")
		)
		(fp_line
			(start 0.12065 -0.2794)
			(end 0.12065 -0.3048)
			(stroke
				(width 0.1)
				(type default)
			)
			(layer "F.Fab")
		)
		(fp_line
			(start 0.67945 -0.3048)
			(end 0.67945 0.3048)
			(stroke
				(width 0.1)
				(type default)
			)
			(layer "F.Fab")
		)
		(fp_line
			(start 0.67945 0.3048)
			(end 0.120396 0.3048)
			(stroke
				(width 0.1)
				(type default)
			)
			(layer "F.Fab")
		)
		(pad "1" smd circle
			(at -0.40005 0)
			(size 0 0)
			(layers "F.Cu" "F.Mask" "F.Paste")
			(net "P3V3_AUX")
		)
		(pad "2" smd circle
			(at 0.40005 0)
			(size 0 0)
			(layers "F.Cu" "F.Mask" "F.Paste")
			(net "GND")
		)
	)
	(footprint ""
		(layer "F.Cu")
		(at 70.52691 -325.682864)
		(property "Reference" "PL44"
			(at 2.853944 -16.649446 0)
			(unlocked yes)
			(layer "F.SilkS")
			(effects
				(font
					(size 0.7874 0.5842)
					(thickness 0.1524)
				)
				(justify left)
			)
		)
		(property "Value" ""
			(at 0 0 0)
			(layer "F.Fab")
			(effects
				(font
					(size 1.27 1.27)
				)
			)
		)
		(duplicate_pad_numbers_are_jumpers no)
		(fp_line
			(start -3.750056 -5.500116)
			(end -2.393442 -5.500116)
			(stroke
				(width 0.1524)
				(type default)
			)
			(layer "F.SilkS")
		)
		(fp_line
			(start -3.750056 5.500116)
			(end -3.750056 -5.500116)
			(stroke
				(width 0.1524)
				(type default)
			)
			(layer "F.SilkS")
		)
		(fp_line
			(start -2.393442 5.500116)
			(end -3.750056 5.500116)
			(stroke
				(width 0.1524)
				(type default)
			)
			(layer "F.SilkS")
		)
		(fp_line
			(start 2.393442 5.500116)
			(end 3.750056 5.500116)
			(stroke
				(width 0.1524)
				(type default)
			)
			(layer "F.SilkS")
		)
		(fp_line
			(start 3.750056 -5.500116)
			(end 2.393442 -5.500116)
			(stroke
				(width 0.1524)
				(type default)
			)
			(layer "F.SilkS")
		)
		(fp_line
			(start 3.750056 5.500116)
			(end 3.750056 -5.500116)
			(stroke
				(width 0.1524)
				(type default)
			)
			(layer "F.SilkS")
		)
		(fp_poly
			(pts
				(xy -3.9116 -4.249928) (xy -4.9276 -3.741928) (xy -4.9276 -4.757928)
			)
			(stroke
				(width 0)
				(type default)
			)
			(fill yes)
			(layer "F.SilkS")
		)
		(fp_line
			(start -3.750056 -5.500116)
			(end -3.750056 5.500116)
			(stroke
				(width 0.1)
				(type default)
			)
			(layer "F.Fab")
		)
		(fp_line
			(start -3.750056 5.500116)
			(end 3.750056 5.500116)
			(stroke
				(width 0.1)
				(type default)
			)
			(layer "F.Fab")
		)
		(fp_line
			(start 3.750056 -5.500116)
			(end -3.750056 -5.500116)
			(stroke
				(width 0.1)
				(type default)
			)
			(layer "F.Fab")
		)
		(fp_line
			(start 3.750056 5.500116)
			(end 3.750056 -5.500116)
			(stroke
				(width 0.1)
				(type default)
			)
			(layer "F.Fab")
		)
		(fp_poly
			(pts
				(xy -4.9276 -4.757928) (xy -4.9276 -3.741928) (xy -3.9116 -4.249928)
			)
			(stroke
				(width 0)
				(type default)
			)
			(fill yes)
			(layer "F.Fab")
		)
		(pad "1" smd rect
			(at 0 -4.249928 270)
			(size 2.413 4.5212)
			(layers "F.Cu" "F.Mask" "F.Paste")
			(net "SW_PVDDCR_CPU1_P1_SW3")
		)
		(pad "2" smd rect
			(at 0 -1.175004 270)
			(size 1.3716 4.5212)
			(layers "F.Cu" "F.Mask" "F.Paste")
			(net "IND_CPU1_P1_CPL2")
		)
		(pad "3" smd rect
			(at 0 1.175004 270)
			(size 1.3716 4.5212)
			(layers "F.Cu" "F.Mask" "F.Paste")
			(net "IND_CPU1_P1_CPL3")
		)
		(pad "4" smd rect
			(at 0 4.249928 270)
			(size 2.413 4.5212)
			(layers "F.Cu" "F.Mask" "F.Paste")
			(net "PVDDCR_CPU1_P1")
		)
	)
	(footprint ""
		(layer "F.Cu")
		(at 83.564476 -352.36912 90)
		(property "Reference" "PC390"
			(at -5.43179 -1.903476 0)
			(unlocked yes)
			(layer "F.SilkS")
			(effects
				(font
					(size 0.7874 0.5842)
					(thickness 0.1524)
				)
				(justify left)
			)
		)
		(property "Value" ""
			(at 0 0 90)
			(layer "F.Fab")
			(effects
				(font
					(size 1.27 1.27)
				)
			)
		)
		(duplicate_pad_numbers_are_jumpers no)
		(fp_line
			(start 3.400044 -3.400044)
			(end -2.146046 -3.400044)
			(stroke
				(width 0.1524)
				(type default)
			)
			(layer "F.SilkS")
		)
		(fp_line
			(start -2.146046 -3.400044)
			(end -3.400044 -2.146046)
			(stroke
				(width 0.1524)
				(type default)
			)
			(layer "F.SilkS")
		)
		(fp_line
			(start -3.400044 -2.146046)
			(end -3.400044 -0.9398)
			(stroke
				(width 0.1524)
				(type default)
			)
			(layer "F.SilkS")
		)
		(fp_line
			(start 3.400044 -0.9398)
			(end 3.400044 -3.400044)
			(stroke
				(width 0.1524)
				(type default)
			)
			(layer "F.SilkS")
		)
		(fp_line
			(start 3.400044 0.9398)
			(end 3.400044 3.400044)
			(stroke
				(width 0.1524)
				(type default)
			)
			(layer "F.SilkS")
		)
		(fp_line
			(start -3.400044 2.146046)
			(end -3.400044 0.9398)
			(stroke
				(width 0.1524)
				(type default)
			)
			(layer "F.SilkS")
		)
		(fp_line
			(start 3.400044 3.400044)
			(end -2.146046 3.400044)
			(stroke
				(width 0.1524)
				(type default)
			)
			(layer "F.SilkS")
		)
		(fp_line
			(start -2.146046 3.400044)
			(end -3.400044 2.146046)
			(stroke
				(width 0.1524)
				(type default)
			)
			(layer "F.SilkS")
		)
		(fp_line
			(start 3.400044 -3.400044)
			(end -3.400044 -3.400044)
			(stroke
				(width 0.1)
				(type default)
			)
			(layer "F.Fab")
		)
		(fp_line
			(start -3.400044 -3.400044)
			(end -3.400044 3.400044)
			(stroke
				(width 0.1)
				(type default)
			)
			(layer "F.Fab")
		)
		(fp_line
			(start 3.400044 3.400044)
			(end 3.400044 -3.400044)
			(stroke
				(width 0.1)
				(type default)
			)
			(layer "F.Fab")
		)
		(fp_line
			(start -3.400044 3.400044)
			(end 3.400044 3.400044)
			(stroke
				(width 0.1)
				(type default)
			)
			(layer "F.Fab")
		)
		(pad "1" smd rect
			(at -2.70002 0)
			(size 1.6002 3.5052)
			(layers "F.Cu" "F.Mask" "F.Paste")
			(net "SW_P12V_AUX_PVDDCR_CPU1_P1_FLT")
		)
		(pad "2" smd rect
			(at 2.70002 0)
			(size 1.6002 3.5052)
			(layers "F.Cu" "F.Mask" "F.Paste")
			(net "GND")
		)
	)
	(footprint ""
		(layer "F.Cu")
		(at 317.210186 -361.061 -90)
		(property "Reference" "PC67"
			(at 0 0 270)
			(layer "F.SilkS")
			(hide yes)
			(effects
				(font
					(size 1.27 1.27)
				)
			)
		)
		(property "Value" ""
			(at 0 0 270)
			(layer "F.Fab")
			(effects
				(font
					(size 1.27 1.27)
				)
			)
		)
		(duplicate_pad_numbers_are_jumpers no)
		(fp_line
			(start -0.7874 0.4064)
			(end -0.7874 -0.4064)
			(stroke
				(width 0.1524)
				(type default)
			)
			(layer "F.SilkS")
		)
		(fp_line
			(start 0.7874 0.4064)
			(end -0.7874 0.4064)
			(stroke
				(width 0.1524)
				(type default)
			)
			(layer "F.SilkS")
		)
		(fp_line
			(start -0.7874 -0.4064)
			(end 0.7874 -0.4064)
			(stroke
				(width 0.1524)
				(type default)
			)
			(layer "F.SilkS")
		)
		(fp_line
			(start 0.7874 -0.4064)
			(end 0.7874 0.4064)
			(stroke
				(width 0.1524)
				(type default)
			)
			(layer "F.SilkS")
		)
		(fp_line
			(start -0.67945 0.3048)
			(end -0.67945 -0.305054)
			(stroke
				(width 0.1)
				(type default)
			)
			(layer "F.Fab")
		)
		(fp_line
			(start -0.12065 0.3048)
			(end -0.67945 0.3048)
			(stroke
				(width 0.1)
				(type default)
			)
			(layer "F.Fab")
		)
		(fp_line
			(start 0.120396 0.3048)
			(end 0.120396 0.2794)
			(stroke
				(width 0.1)
				(type default)
			)
			(layer "F.Fab")
		)
		(fp_line
			(start 0.67945 0.3048)
			(end 0.120396 0.3048)
			(stroke
				(width 0.1)
				(type default)
			)
			(layer "F.Fab")
		)
		(fp_line
			(start -0.12065 0.2794)
			(end -0.12065 0.3048)
			(stroke
				(width 0.1)
				(type default)
			)
			(layer "F.Fab")
		)
		(fp_line
			(start 0.120396 0.2794)
			(end -0.12065 0.2794)
			(stroke
				(width 0.1)
				(type default)
			)
			(layer "F.Fab")
		)
		(fp_line
			(start -0.12065 -0.2794)
			(end 0.12065 -0.2794)
			(stroke
				(width 0.1)
				(type default)
			)
			(layer "F.Fab")
		)
		(fp_line
			(start 0.12065 -0.2794)
			(end 0.12065 -0.3048)
			(stroke
				(width 0.1)
				(type default)
			)
			(layer "F.Fab")
		)
		(fp_line
			(start 0.12065 -0.3048)
			(end 0.67945 -0.3048)
			(stroke
				(width 0.1)
				(type default)
			)
			(layer "F.Fab")
		)
		(fp_line
			(start 0.67945 -0.3048)
			(end 0.67945 0.3048)
			(stroke
				(width 0.1)
				(type default)
			)
			(layer "F.Fab")
		)
		(fp_line
			(start -0.67945 -0.305054)
			(end -0.12065 -0.305054)
			(stroke
				(width 0.1)
				(type default)
			)
			(layer "F.Fab")
		)
		(fp_line
			(start -0.12065 -0.305054)
			(end -0.12065 -0.2794)
			(stroke
				(width 0.1)
				(type default)
			)
			(layer "F.Fab")
		)
		(pad "1" smd circle
			(at -0.40005 0 270)
			(size 0 0)
			(layers "F.Cu" "F.Mask" "F.Paste")
			(net "PVDDCR_CPU1_P0_VMON")
		)
		(pad "2" smd circle
			(at 0.40005 0 270)
			(size 0 0)
			(layers "F.Cu" "F.Mask" "F.Paste")
			(net "GND")
		)
	)
)
